# T6G (Grand Teton) — schematic netlist excerpt (pin names and nets, part order shuffled) for the footprints in the layout excerpt that follows; sources: Cadence DE-HDL packaged netlist, KiCad conversion of 04192023_DAF0TMB3IC0_F0TG_MB_C_brd_V02_OCP.brd

C2430  Q_CAP  22UF 4V 20% X6S  pkg C0402  page 74 : A = PVDDCR_SOC_P1 ; B = GND
C461  Q_CAP  1000PF 50V 5% X7R  pkg 0402  page 193 : A = PVDDCR_SOC_P0_EN_RC ; B = GND

(kicad_pcb
	(version 20260206)
	(generator "pcbnew")
	(generator_version "10.0")
	(general
		(thickness 1.6)
		(legacy_teardrops no)
	)
	(paper "A4")
	(title_block
		(title "04192023_DAF0TMB3IC0_F0TG_MB_C_brd_V02_OCP.brd")
		(comment 1 "Grand Teton / footprints 5284-5285 of 8354")
	)
	(layers
		(0 "F.Cu" signal "TOP")
		(4 "In1.Cu" signal "GND")
		(6 "In2.Cu" signal "IN1")
		(8 "In3.Cu" signal "GND1")
		(10 "In4.Cu" signal "IN2")
		(12 "In5.Cu" signal "GND2")
		(14 "In6.Cu" signal "IN3")
		(16 "In7.Cu" signal "GND3")
		(18 "In8.Cu" signal "VCC")
		(20 "In9.Cu" signal "VCC1")
		(22 "In10.Cu" signal "GND4")
		(24 "In11.Cu" signal "IN4")
		(26 "In12.Cu" signal "GND5")
		(28 "In13.Cu" signal "IN5")
		(30 "In14.Cu" signal "GND6")
		(32 "In15.Cu" signal "IN6")
		(34 "In16.Cu" signal "GND7")
		(2 "B.Cu" signal "BOTTOM")
		(9 "F.Adhes" user "F.Adhesive")
		(11 "B.Adhes" user "B.Adhesive")
		(13 "F.Paste" user "Package Geometry/Pastemask Top")
		(15 "B.Paste" user "Package Geometry/Pastemask Bottom")
		(5 "F.SilkS" user "Ref Des/Silkscreen Top")
		(7 "B.SilkS" user "Ref Des/Silkscreen Bottom")
		(1 "F.Mask" user "Board Geometry/Soldermask Top")
		(3 "B.Mask" user "Board Geometry/Soldermask Bottom")
		(17 "Dwgs.User" user "User.Drawings")
		(19 "Cmts.User" user "User.Comments")
		(21 "Eco1.User" user "User.Eco1")
		(23 "Eco2.User" user "User.Eco2")
		(25 "Edge.Cuts" user "Board Geometry/Outline")
		(27 "Margin" user)
		(31 "F.CrtYd" user "Package Geometry/Place Bound Top")
		(29 "B.CrtYd" user "Package Geometry/Place Bound Bottom")
		(35 "F.Fab" user "Ref Des/Assembly Top")
		(33 "B.Fab" user "Ref Des/Assembly Bottom")
	)
	(footprint ""
		(layer "B.Cu")
		(at 117.895624 -256.505456)
		(property "Reference" "C2430"
			(at 0 0 0)
			(layer "B.SilkS")
			(hide yes)
			(effects
				(font
					(size 1.27 1.27)
				)
				(justify mirror)
			)
		)
		(property "Value" ""
			(at 0 0 0)
			(layer "B.Fab")
			(effects
				(font
					(size 1.27 1.27)
				)
				(justify mirror)
			)
		)
		(duplicate_pad_numbers_are_jumpers no)
		(fp_line
			(start -0.7874 -0.4064)
			(end -0.7874 0.4064)
			(stroke
				(width 0.1524)
				(type default)
			)
			(layer "B.SilkS")
		)
		(fp_line
			(start -0.7874 0.4064)
			(end 0.7874 0.4064)
			(stroke
				(width 0.1524)
				(type default)
			)
			(layer "B.SilkS")
		)
		(fp_line
			(start 0.7874 -0.4064)
			(end -0.7874 -0.4064)
			(stroke
				(width 0.1524)
				(type default)
			)
			(layer "B.SilkS")
		)
		(fp_line
			(start 0.7874 0.4064)
			(end 0.7874 -0.4064)
			(stroke
				(width 0.1524)
				(type default)
			)
			(layer "B.SilkS")
		)
		(fp_line
			(start -0.67945 -0.3048)
			(end -0.67945 0.3048)
			(stroke
				(width 0.1)
				(type default)
			)
			(layer "B.Fab")
		)
		(fp_line
			(start -0.67945 0.3048)
			(end -0.120396 0.3048)
			(stroke
				(width 0.1)
				(type default)
			)
			(layer "B.Fab")
		)
		(fp_line
			(start -0.12065 -0.3048)
			(end -0.67945 -0.3048)
			(stroke
				(width 0.1)
				(type default)
			)
			(layer "B.Fab")
		)
		(fp_line
			(start -0.12065 -0.2794)
			(end -0.12065 -0.3048)
			(stroke
				(width 0.1)
				(type default)
			)
			(layer "B.Fab")
		)
		(fp_line
			(start -0.120396 0.2794)
			(end 0.12065 0.2794)
			(stroke
				(width 0.1)
				(type default)
			)
			(layer "B.Fab")
		)
		(fp_line
			(start -0.120396 0.3048)
			(end -0.120396 0.2794)
			(stroke
				(width 0.1)
				(type default)
			)
			(layer "B.Fab")
		)
		(fp_line
			(start 0.12065 -0.305054)
			(end 0.12065 -0.2794)
			(stroke
				(width 0.1)
				(type default)
			)
			(layer "B.Fab")
		)
		(fp_line
			(start 0.12065 -0.2794)
			(end -0.12065 -0.2794)
			(stroke
				(width 0.1)
				(type default)
			)
			(layer "B.Fab")
		)
		(fp_line
			(start 0.12065 0.2794)
			(end 0.12065 0.3048)
			(stroke
				(width 0.1)
				(type default)
			)
			(layer "B.Fab")
		)
		(fp_line
			(start 0.12065 0.3048)
			(end 0.67945 0.3048)
			(stroke
				(width 0.1)
				(type default)
			)
			(layer "B.Fab")
		)
		(fp_line
			(start 0.67945 -0.305054)
			(end 0.12065 -0.305054)
			(stroke
				(width 0.1)
				(type default)
			)
			(layer "B.Fab")
		)
		(fp_line
			(start 0.67945 0.3048)
			(end 0.67945 -0.305054)
			(stroke
				(width 0.1)
				(type default)
			)
			(layer "B.Fab")
		)
		(pad "1" smd circle
			(at 0.40005 0 180)
			(size 0 0)
			(layers "B.Cu" "B.Mask" "B.Paste")
			(net "PVDDCR_SOC_P1")
		)
		(pad "2" smd circle
			(at -0.40005 0 180)
			(size 0 0)
			(layers "B.Cu" "B.Mask" "B.Paste")
			(net "GND")
		)
	)
	(footprint ""
		(layer "B.Cu")
		(at 367.671858 -136.986772)
		(property "Reference" "C461"
			(at 0 0 0)
			(layer "B.SilkS")
			(hide yes)
			(effects
				(font
					(size 1.27 1.27)
				)
				(justify mirror)
			)
		)
		(property "Value" ""
			(at 0 0 0)
			(layer "B.Fab")
			(effects
				(font
					(size 1.27 1.27)
				)
				(justify mirror)
			)
		)
		(duplicate_pad_numbers_are_jumpers no)
		(fp_line
			(start -0.7874 -0.4064)
			(end -0.7874 0.4064)
			(stroke
				(width 0.1524)
				(type default)
			)
			(layer "B.SilkS")
		)
		(fp_line
			(start -0.7874 0.4064)
			(end 0.7874 0.4064)
			(stroke
				(width 0.1524)
				(type default)
			)
			(layer "B.SilkS")
		)
		(fp_line
			(start 0.7874 -0.4064)
			(end -0.7874 -0.4064)
			(stroke
				(width 0.1524)
				(type default)
			)
			(layer "B.SilkS")
		)
		(fp_line
			(start 0.7874 0.4064)
			(end 0.7874 -0.4064)
			(stroke
				(width 0.1524)
				(type default)
			)
			(layer "B.SilkS")
		)
		(fp_line
			(start -0.67945 -0.3048)
			(end -0.67945 0.3048)
			(stroke
				(width 0.1)
				(type default)
			)
			(layer "B.Fab")
		)
		(fp_line
			(start -0.67945 0.3048)
			(end -0.120396 0.3048)
			(stroke
				(width 0.1)
				(type default)
			)
			(layer "B.Fab")
		)
		(fp_line
			(start -0.12065 -0.3048)
			(end -0.67945 -0.3048)
			(stroke
				(width 0.1)
				(type default)
			)
			(layer "B.Fab")
		)
		(fp_line
			(start -0.12065 -0.2794)
			(end -0.12065 -0.3048)
			(stroke
				(width 0.1)
				(type default)
			)
			(layer "B.Fab")
		)
		(fp_line
			(start -0.120396 0.2794)
			(end 0.12065 0.2794)
			(stroke
				(width 0.1)
				(type default)
			)
			(layer "B.Fab")
		)
		(fp_line
			(start -0.120396 0.3048)
			(end -0.120396 0.2794)
			(stroke
				(width 0.1)
				(type default)
			)
			(layer "B.Fab")
		)
		(fp_line
			(start 0.12065 -0.305054)
			(end 0.12065 -0.2794)
			(stroke
				(width 0.1)
				(type default)
			)
			(layer "B.Fab")
		)
		(fp_line
			(start 0.12065 -0.2794)
			(end -0.12065 -0.2794)
			(stroke
				(width 0.1)
				(type default)
			)
			(layer "B.Fab")
		)
		(fp_line
			(start 0.12065 0.2794)
			(end 0.12065 0.3048)
			(stroke
				(width 0.1)
				(type default)
			)
			(layer "B.Fab")
		)
		(fp_line
			(start 0.12065 0.3048)
			(end 0.67945 0.3048)
			(stroke
				(width 0.1)
				(type default)
			)
			(layer "B.Fab")
		)
		(fp_line
			(start 0.67945 -0.305054)
			(end 0.12065 -0.305054)
			(stroke
				(width 0.1)
				(type default)
			)
			(layer "B.Fab")
		)
		(fp_line
			(start 0.67945 0.3048)
			(end 0.67945 -0.305054)
			(stroke
				(width 0.1)
				(type default)
			)
			(layer "B.Fab")
		)
		(pad "1" smd circle
			(at 0.40005 0 180)
			(size 0 0)
			(layers "B.Cu" "B.Mask" "B.Paste")
			(net "PVDDCR_SOC_P0_EN_RC")
		)
		(pad "2" smd circle
			(at -0.40005 0 180)
			(size 0 0)
			(layers "B.Cu" "B.Mask" "B.Paste")
			(net "GND")
		)
	)
)
